(kicad_pcb
	(version 20260206)
	(generator "pcbnew")
	(generator_version "10.0")
	(general
		(thickness 1.6)
		(legacy_teardrops no)
	)
	(paper "A4")
	(title_block
		(title "Bryce Canyon_IOM_M2_16342-2_OCP.brd")
		(comment 1 "Bryce Canyon / footprints 682-689 of 1146")
	)
	(layers
		(0 "F.Cu" signal "TOP")
		(4 "In1.Cu" signal "L2GND")
		(6 "In2.Cu" signal "L3")
		(8 "In3.Cu" signal "L4VCC")
		(10 "In4.Cu" signal "L5VCC")
		(12 "In5.Cu" signal "L6")
		(14 "In6.Cu" signal "L7GND")
		(2 "B.Cu" signal "BOTTOM")
		(9 "F.Adhes" user "F.Adhesive")
		(11 "B.Adhes" user "B.Adhesive")
		(13 "F.Paste" user "Package Geometry/Pastemask Top")
		(15 "B.Paste" user "Package Geometry/Pastemask Bottom")
		(5 "F.SilkS" user "Ref Des/Silkscreen Top")
		(7 "B.SilkS" user "Ref Des/Silkscreen Bottom")
		(1 "F.Mask" user "Board Geometry/Soldermask Top")
		(3 "B.Mask" user "Board Geometry/Soldermask Bottom")
		(17 "Dwgs.User" user "User.Drawings")
		(19 "Cmts.User" user "User.Comments")
		(21 "Eco1.User" user "User.Eco1")
		(23 "Eco2.User" user "User.Eco2")
		(25 "Edge.Cuts" user "Board Geometry/Outline")
		(27 "Margin" user)
		(31 "F.CrtYd" user "Package Geometry/Place Bound Top")
		(29 "B.CrtYd" user "Package Geometry/Place Bound Bottom")
		(35 "F.Fab" user "Ref Des/Assembly Top")
		(33 "B.Fab" user "Ref Des/Assembly Bottom")
	)
	(footprint ""
		(layer "F.Cu")
		(at 122.231404 -14.167612 90)
		(property "Reference" "C129"
			(at 0 0 90)
			(layer "F.SilkS")
			(hide yes)
			(effects
				(font
					(size 1.27 1.27)
				)
			)
		)
		(property "Value" "SC1KP50V2KX-1GP"
			(at 1.1811 -2.7051 90)
			(unlocked yes)
			(layer "F.Fab")
			(hide yes)
			(effects
				(font
					(size 1.016 1.016)
					(thickness 0.1524)
				)
			)
		)
		(property "Device Type" "C402H22"
			(at 1.1811 -4.2291 90)
			(unlocked yes)
			(layer "F.Fab")
			(hide yes)
			(effects
				(font
					(size 1.016 1.016)
					(thickness 0.1524)
				)
			)
		)
		(duplicate_pad_numbers_are_jumpers no)
		(fp_rect
			(start -0.4318 0.9525)
			(end 0.4318 -0.9525)
			(stroke
				(width 0)
				(type default)
			)
			(fill no)
			(layer "F.CrtYd")
		)
		(fp_rect
			(start -0.4318 0.9525)
			(end 0.4318 -0.9525)
			(stroke
				(width 0)
				(type default)
			)
			(fill no)
			(layer "F.Fab")
		)
		(pad "1" smd custom
			(at 0 -0.4445 90)
			(size 0.1524 0.1524)
			(layers "F.Cu" "F.Mask" "F.Paste")
			(net "MB0_TEMP")
			(options
				(clearance outline)
				(anchor circle)
			)
			(primitives
				(gr_poly
					(pts
						(arc
							(start 0.3048 -0.2032)
							(mid 0.275042 -0.275042)
							(end 0.2032 -0.3048)
						)
						(arc
							(start -0.2032 -0.3048)
							(mid -0.275042 -0.275042)
							(end -0.3048 -0.2032)
						)
						(arc
							(start -0.3048 0.2032)
							(mid -0.275042 0.275042)
							(end -0.2032 0.3048)
						)
						(arc
							(start 0.2032 0.3048)
							(mid 0.275042 0.275042)
							(end 0.3048 0.2032)
						)
					)
					(width 0)
					(fill yes)
				)
			)
		)
		(pad "2" smd custom
			(at 0 0.4445 90)
			(size 0.1524 0.1524)
			(layers "F.Cu" "F.Mask" "F.Paste")
			(net "GND")
			(options
				(clearance outline)
				(anchor circle)
			)
			(primitives
				(gr_poly
					(pts
						(arc
							(start 0.3048 -0.2032)
							(mid 0.275042 -0.275042)
							(end 0.2032 -0.3048)
						)
						(arc
							(start -0.2032 -0.3048)
							(mid -0.275042 -0.275042)
							(end -0.3048 -0.2032)
						)
						(arc
							(start -0.3048 0.2032)
							(mid -0.275042 0.275042)
							(end -0.2032 0.3048)
						)
						(arc
							(start 0.2032 0.3048)
							(mid 0.275042 0.275042)
							(end 0.3048 0.2032)
						)
					)
					(width 0)
					(fill yes)
				)
			)
		)
	)
	(footprint ""
		(layer "F.Cu")
		(at 68.5038 -116.3828 -90)
		(property "Reference" "R268"
			(at 0 0 270)
			(layer "F.SilkS")
			(hide yes)
			(effects
				(font
					(size 1.27 1.27)
				)
			)
		)
		(property "Value" "2K2R2J-2-GP"
			(at 0.064008 -3.993896 270)
			(unlocked yes)
			(layer "F.Fab")
			(hide yes)
			(effects
				(font
					(size 1.016 1.016)
					(thickness 0.1524)
				)
			)
		)
		(property "Device Type" "R402H16"
			(at 0.064008 -5.517896 270)
			(unlocked yes)
			(layer "F.Fab")
			(hide yes)
			(effects
				(font
					(size 1.016 1.016)
					(thickness 0.1524)
				)
			)
		)
		(duplicate_pad_numbers_are_jumpers no)
		(fp_line
			(start -0.508 -0.9398)
			(end -0.508 0.9398)
			(stroke
				(width 0.1524)
				(type default)
			)
			(layer "F.SilkS")
		)
		(fp_line
			(start 0.508 -0.9398)
			(end -0.508 -0.9398)
			(stroke
				(width 0.1524)
				(type default)
			)
			(layer "F.SilkS")
		)
		(fp_rect
			(start -0.508 0.9398)
			(end 0.508 -0.9398)
			(stroke
				(width 0)
				(type default)
			)
			(fill no)
			(layer "F.CrtYd")
		)
		(fp_rect
			(start -0.508 0.9398)
			(end 0.508 -0.9398)
			(stroke
				(width 0)
				(type default)
			)
			(fill no)
			(layer "F.Fab")
		)
		(pad "1" smd custom
			(at 0 -0.4445 270)
			(size 0.1397 0.1397)
			(layers "F.Cu" "F.Mask" "F.Paste")
			(net "P3V3_STBY")
			(options
				(clearance outline)
				(anchor circle)
			)
			(primitives
				(gr_poly
					(pts
						(arc
							(start -0.1778 -0.2794)
							(mid -0.249642 -0.249642)
							(end -0.2794 -0.1778)
						)
						(arc
							(start -0.2794 0.1778)
							(mid -0.249642 0.249642)
							(end -0.1778 0.2794)
						)
						(arc
							(start 0.1778 0.2794)
							(mid 0.249642 0.249642)
							(end 0.2794 0.1778)
						)
						(arc
							(start 0.2794 -0.1778)
							(mid 0.249642 -0.249642)
							(end 0.1778 -0.2794)
						)
					)
					(width 0)
					(fill yes)
				)
			)
		)
		(pad "2" smd custom
			(at 0 0.4445 270)
			(size 0.1397 0.1397)
			(layers "F.Cu" "F.Mask" "F.Paste")
			(net "PU_IBMC_BT_HOLD_N")
			(options
				(clearance outline)
				(anchor circle)
			)
			(primitives
				(gr_poly
					(pts
						(arc
							(start -0.1778 -0.2794)
							(mid -0.249642 -0.249642)
							(end -0.2794 -0.1778)
						)
						(arc
							(start -0.2794 0.1778)
							(mid -0.249642 0.249642)
							(end -0.1778 0.2794)
						)
						(arc
							(start 0.1778 0.2794)
							(mid 0.249642 0.249642)
							(end 0.2794 0.1778)
						)
						(arc
							(start 0.2794 -0.1778)
							(mid 0.249642 -0.249642)
							(end 0.1778 -0.2794)
						)
					)
					(width 0)
					(fill yes)
				)
			)
		)
	)
	(footprint ""
		(layer "F.Cu")
		(at 74.423016 -174.78248 -90)
		(property "Reference" "C190"
			(at 0 0 270)
			(layer "F.SilkS")
			(hide yes)
			(effects
				(font
					(size 1.27 1.27)
				)
			)
		)
		(property "Value" "SC1KP50V2KX-1GP"
			(at 1.1811 -2.7051 270)
			(unlocked yes)
			(layer "F.Fab")
			(hide yes)
			(effects
				(font
					(size 1.016 1.016)
					(thickness 0.1524)
				)
			)
		)
		(property "Device Type" "C402H22"
			(at 1.1811 -4.2291 270)
			(unlocked yes)
			(layer "F.Fab")
			(hide yes)
			(effects
				(font
					(size 1.016 1.016)
					(thickness 0.1524)
				)
			)
		)
		(duplicate_pad_numbers_are_jumpers no)
		(fp_rect
			(start -0.4318 0.9525)
			(end 0.4318 -0.9525)
			(stroke
				(width 0)
				(type default)
			)
			(fill no)
			(layer "F.CrtYd")
		)
		(fp_rect
			(start -0.4318 0.9525)
			(end 0.4318 -0.9525)
			(stroke
				(width 0)
				(type default)
			)
			(fill no)
			(layer "F.Fab")
		)
		(pad "1" smd custom
			(at 0 -0.4445 270)
			(size 0.1524 0.1524)
			(layers "F.Cu" "F.Mask" "F.Paste")
			(net "TPS74801_P2V5_STBY_OUT")
			(options
				(clearance outline)
				(anchor circle)
			)
			(primitives
				(gr_poly
					(pts
						(arc
							(start 0.3048 -0.2032)
							(mid 0.275042 -0.275042)
							(end 0.2032 -0.3048)
						)
						(arc
							(start -0.2032 -0.3048)
							(mid -0.275042 -0.275042)
							(end -0.3048 -0.2032)
						)
						(arc
							(start -0.3048 0.2032)
							(mid -0.275042 0.275042)
							(end -0.2032 0.3048)
						)
						(arc
							(start 0.2032 0.3048)
							(mid 0.275042 0.275042)
							(end 0.3048 0.2032)
						)
					)
					(width 0)
					(fill yes)
				)
			)
		)
		(pad "2" smd custom
			(at 0 0.4445 270)
			(size 0.1524 0.1524)
			(layers "F.Cu" "F.Mask" "F.Paste")
			(net "TPS74801_P2V5_STBY_FB")
			(options
				(clearance outline)
				(anchor circle)
			)
			(primitives
				(gr_poly
					(pts
						(arc
							(start 0.3048 -0.2032)
							(mid 0.275042 -0.275042)
							(end 0.2032 -0.3048)
						)
						(arc
							(start -0.2032 -0.3048)
							(mid -0.275042 -0.275042)
							(end -0.3048 -0.2032)
						)
						(arc
							(start -0.3048 0.2032)
							(mid -0.275042 0.275042)
							(end -0.2032 0.3048)
						)
						(arc
							(start 0.2032 0.3048)
							(mid 0.275042 0.275042)
							(end 0.3048 0.2032)
						)
					)
					(width 0)
					(fill yes)
				)
			)
		)
	)
	(footprint ""
		(layer "F.Cu")
		(at 11.806936 -170.6372 -90)
		(property "Reference" "C233"
			(at 0 0 270)
			(layer "F.SilkS")
			(hide yes)
			(effects
				(font
					(size 1.27 1.27)
				)
			)
		)
		(property "Value" "SCD1U16V2KX-3GP"
			(at 1.1811 -2.7051 270)
			(unlocked yes)
			(layer "F.Fab")
			(hide yes)
			(effects
				(font
					(size 1.016 1.016)
					(thickness 0.1524)
				)
			)
		)
		(property "Device Type" "C402H22"
			(at 1.1811 -4.2291 270)
			(unlocked yes)
			(layer "F.Fab")
			(hide yes)
			(effects
				(font
					(size 1.016 1.016)
					(thickness 0.1524)
				)
			)
		)
		(duplicate_pad_numbers_are_jumpers no)
		(fp_rect
			(start -0.4318 0.9525)
			(end 0.4318 -0.9525)
			(stroke
				(width 0)
				(type default)
			)
			(fill no)
			(layer "F.CrtYd")
		)
		(fp_rect
			(start -0.4318 0.9525)
			(end 0.4318 -0.9525)
			(stroke
				(width 0)
				(type default)
			)
			(fill no)
			(layer "F.Fab")
		)
		(pad "1" smd custom
			(at 0 -0.4445 270)
			(size 0.1524 0.1524)
			(layers "F.Cu" "F.Mask" "F.Paste")
			(net "TPS74801_P1V2_STBY_EN")
			(options
				(clearance outline)
				(anchor circle)
			)
			(primitives
				(gr_poly
					(pts
						(arc
							(start 0.3048 -0.2032)
							(mid 0.275042 -0.275042)
							(end 0.2032 -0.3048)
						)
						(arc
							(start -0.2032 -0.3048)
							(mid -0.275042 -0.275042)
							(end -0.3048 -0.2032)
						)
						(arc
							(start -0.3048 0.2032)
							(mid -0.275042 0.275042)
							(end -0.2032 0.3048)
						)
						(arc
							(start 0.2032 0.3048)
							(mid 0.275042 0.275042)
							(end 0.3048 0.2032)
						)
					)
					(width 0)
					(fill yes)
				)
			)
		)
		(pad "2" smd custom
			(at 0 0.4445 270)
			(size 0.1524 0.1524)
			(layers "F.Cu" "F.Mask" "F.Paste")
			(net "GND")
			(options
				(clearance outline)
				(anchor circle)
			)
			(primitives
				(gr_poly
					(pts
						(arc
							(start 0.3048 -0.2032)
							(mid 0.275042 -0.275042)
							(end 0.2032 -0.3048)
						)
						(arc
							(start -0.2032 -0.3048)
							(mid -0.275042 -0.275042)
							(end -0.3048 -0.2032)
						)
						(arc
							(start -0.3048 0.2032)
							(mid -0.275042 0.275042)
							(end -0.2032 0.3048)
						)
						(arc
							(start 0.2032 0.3048)
							(mid 0.275042 0.275042)
							(end 0.3048 0.2032)
						)
					)
					(width 0)
					(fill yes)
				)
			)
		)
	)
	(footprint ""
		(layer "F.Cu")
		(at 182.4482 -99.695)
		(property "Reference" "R557"
			(at 0 0 0)
			(layer "F.SilkS")
			(hide yes)
			(effects
				(font
					(size 1.27 1.27)
				)
			)
		)
		(property "Value" "0R2J-2-GP"
			(at 0.064008 -3.993896 0)
			(unlocked yes)
			(layer "F.Fab")
			(hide yes)
			(effects
				(font
					(size 1.016 1.016)
					(thickness 0.1524)
				)
			)
		)
		(property "Device Type" "R402H16"
			(at 0.064008 -5.517896 0)
			(unlocked yes)
			(layer "F.Fab")
			(hide yes)
			(effects
				(font
					(size 1.016 1.016)
					(thickness 0.1524)
				)
			)
		)
		(duplicate_pad_numbers_are_jumpers no)
		(fp_line
			(start -0.508 -0.9398)
			(end -0.508 0.9398)
			(stroke
				(width 0.1524)
				(type default)
			)
			(layer "F.SilkS")
		)
		(fp_line
			(start 0.508 -0.9398)
			(end -0.508 -0.9398)
			(stroke
				(width 0.1524)
				(type default)
			)
			(layer "F.SilkS")
		)
		(fp_rect
			(start -0.508 0.9398)
			(end 0.508 -0.9398)
			(stroke
				(width 0)
				(type default)
			)
			(fill no)
			(layer "F.CrtYd")
		)
		(fp_rect
			(start -0.508 0.9398)
			(end 0.508 -0.9398)
			(stroke
				(width 0)
				(type default)
			)
			(fill no)
			(layer "F.Fab")
		)
		(pad "1" smd custom
			(at 0 -0.4445)
			(size 0.1397 0.1397)
			(layers "F.Cu" "F.Mask" "F.Paste")
			(net "TEMP_1_SCL")
			(options
				(clearance outline)
				(anchor circle)
			)
			(primitives
				(gr_poly
					(pts
						(arc
							(start -0.1778 -0.2794)
							(mid -0.249642 -0.249642)
							(end -0.2794 -0.1778)
						)
						(arc
							(start -0.2794 0.1778)
							(mid -0.249642 0.249642)
							(end -0.1778 0.2794)
						)
						(arc
							(start 0.1778 0.2794)
							(mid 0.249642 0.249642)
							(end 0.2794 0.1778)
						)
						(arc
							(start 0.2794 -0.1778)
							(mid 0.249642 -0.249642)
							(end 0.1778 -0.2794)
						)
					)
					(width 0)
					(fill yes)
				)
			)
		)
		(pad "2" smd custom
			(at 0 0.4445)
			(size 0.1397 0.1397)
			(layers "F.Cu" "F.Mask" "F.Paste")
			(net "I2C_IOM_SCL")
			(options
				(clearance outline)
				(anchor circle)
			)
			(primitives
				(gr_poly
					(pts
						(arc
							(start -0.1778 -0.2794)
							(mid -0.249642 -0.249642)
							(end -0.2794 -0.1778)
						)
						(arc
							(start -0.2794 0.1778)
							(mid -0.249642 0.249642)
							(end -0.1778 0.2794)
						)
						(arc
							(start 0.1778 0.2794)
							(mid 0.249642 0.249642)
							(end 0.2794 0.1778)
						)
						(arc
							(start 0.2794 -0.1778)
							(mid 0.249642 -0.249642)
							(end 0.1778 -0.2794)
						)
					)
					(width 0)
					(fill yes)
				)
			)
		)
	)
	(footprint ""
		(layer "F.Cu")
		(at 184.2008 -111.0234)
		(property "Reference" "R546"
			(at 0 0 0)
			(layer "F.SilkS")
			(hide yes)
			(effects
				(font
					(size 1.27 1.27)
				)
			)
		)
		(property "Value" "4K7R2F-GP"
			(at 0.064008 -3.993896 0)
			(unlocked yes)
			(layer "F.Fab")
			(hide yes)
			(effects
				(font
					(size 1.016 1.016)
					(thickness 0.1524)
				)
			)
		)
		(property "Device Type" "R402H16"
			(at 0.064008 -5.517896 0)
			(unlocked yes)
			(layer "F.Fab")
			(hide yes)
			(effects
				(font
					(size 1.016 1.016)
					(thickness 0.1524)
				)
			)
		)
		(duplicate_pad_numbers_are_jumpers no)
		(fp_line
			(start -0.508 -0.9398)
			(end -0.508 0.9398)
			(stroke
				(width 0.1524)
				(type default)
			)
			(layer "F.SilkS")
		)
		(fp_line
			(start 0.508 -0.9398)
			(end -0.508 -0.9398)
			(stroke
				(width 0.1524)
				(type default)
			)
			(layer "F.SilkS")
		)
		(fp_rect
			(start -0.508 0.9398)
			(end 0.508 -0.9398)
			(stroke
				(width 0)
				(type default)
			)
			(fill no)
			(layer "F.CrtYd")
		)
		(fp_rect
			(start -0.508 0.9398)
			(end 0.508 -0.9398)
			(stroke
				(width 0)
				(type default)
			)
			(fill no)
			(layer "F.Fab")
		)
		(pad "1" smd custom
			(at 0 -0.4445)
			(size 0.1397 0.1397)
			(layers "F.Cu" "F.Mask" "F.Paste")
			(net "P3V3_STBY")
			(options
				(clearance outline)
				(anchor circle)
			)
			(primitives
				(gr_poly
					(pts
						(arc
							(start -0.1778 -0.2794)
							(mid -0.249642 -0.249642)
							(end -0.2794 -0.1778)
						)
						(arc
							(start -0.2794 0.1778)
							(mid -0.249642 0.249642)
							(end -0.1778 0.2794)
						)
						(arc
							(start 0.1778 0.2794)
							(mid 0.249642 0.249642)
							(end 0.2794 0.1778)
						)
						(arc
							(start 0.2794 -0.1778)
							(mid 0.249642 -0.249642)
							(end 0.1778 -0.2794)
						)
					)
					(width 0)
					(fill yes)
				)
			)
		)
		(pad "2" smd custom
			(at 0 0.4445)
			(size 0.1397 0.1397)
			(layers "F.Cu" "F.Mask" "F.Paste")
			(net "TEMP_1_A1")
			(options
				(clearance outline)
				(anchor circle)
			)
			(primitives
				(gr_poly
					(pts
						(arc
							(start -0.1778 -0.2794)
							(mid -0.249642 -0.249642)
							(end -0.2794 -0.1778)
						)
						(arc
							(start -0.2794 0.1778)
							(mid -0.249642 0.249642)
							(end -0.1778 0.2794)
						)
						(arc
							(start 0.1778 0.2794)
							(mid 0.249642 0.249642)
							(end 0.2794 0.1778)
						)
						(arc
							(start 0.2794 -0.1778)
							(mid 0.249642 -0.249642)
							(end 0.1778 -0.2794)
						)
					)
					(width 0)
					(fill yes)
				)
			)
		)
	)
	(footprint ""
		(layer "F.Cu")
		(at 82.457544 -160.376616 180)
		(property "Reference" "C235"
			(at 0 0 180)
			(layer "F.SilkS")
			(hide yes)
			(effects
				(font
					(size 1.27 1.27)
				)
			)
		)
		(property "Value" "SC10U6D3V5KX-4GP"
			(at -0.0762 -6.1214 180)
			(unlocked yes)
			(layer "F.Fab")
			(hide yes)
			(effects
				(font
					(size 1.016 1.016)
					(thickness 0.1524)
				)
			)
		)
		(property "Device Type" "C805H58"
			(at -0.0762 -8.1534 180)
			(unlocked yes)
			(layer "F.Fab")
			(hide yes)
			(effects
				(font
					(size 1.016 1.016)
					(thickness 0.1524)
				)
			)
		)
		(duplicate_pad_numbers_are_jumpers no)
		(fp_line
			(start 0.635 0)
			(end -0.635 0)
			(stroke
				(width 0.508)
				(type default)
			)
			(layer "F.SilkS")
		)
		(fp_rect
			(start -0.9652 1.778)
			(end 0.9652 -1.778)
			(stroke
				(width 0)
				(type default)
			)
			(fill no)
			(layer "F.CrtYd")
		)
		(fp_poly
			(pts
				(xy -0.9652 -1.778) (xy 0.9652 -1.778) (xy 0.9652 1.778) (xy -0.9652 1.778)
			)
			(stroke
				(width 0)
				(type default)
			)
			(fill no)
			(layer "F.Fab")
		)
		(pad "1" smd rect
			(at 0 -0.9652 180)
			(size 1.397 1.143)
			(layers "F.Cu" "F.Mask" "F.Paste")
			(net "TPS74801_P1V15_STBY_OUT")
		)
		(pad "2" smd rect
			(at 0 0.9652 180)
			(size 1.397 1.143)
			(layers "F.Cu" "F.Mask" "F.Paste")
			(net "GND")
		)
	)
	(footprint ""
		(layer "F.Cu")
		(at 171.106338 -9.120378 -90)
		(property "Reference" "G4"
			(at 0 0 270)
			(layer "F.SilkS")
			(hide yes)
			(effects
				(font
					(size 1.27 1.27)
				)
			)
		)
		(property "Value" "GAP-CLOSE-PWR-4-GP"
			(at -2.4638 -0.5461 270)
			(unlocked yes)
			(layer "F.Fab")
			(hide yes)
			(effects
				(font
					(size 1.016 1.016)
					(thickness 0.1524)
				)
			)
		)
		(property "Device Type" "GAP-CLOSE-PWR-4"
			(at -2.4638 -2.0701 270)
			(unlocked yes)
			(layer "F.Fab")
			(hide yes)
			(effects
				(font
					(size 1.016 1.016)
					(thickness 0.1524)
				)
			)
		)
		(duplicate_pad_numbers_are_jumpers no)
		(fp_rect
			(start -0.2794 0.254)
			(end 0.2794 -0.254)
			(stroke
				(width 0)
				(type default)
			)
			(fill no)
			(layer "F.CrtYd")
		)
		(fp_rect
			(start -0.2794 0.254)
			(end 0.2794 -0.254)
			(stroke
				(width 0)
				(type default)
			)
			(fill no)
			(layer "F.Fab")
		)
		(pad "1" smd rect
			(at -0.0635 0 270)
			(size 0.1778 0.254)
			(layers "F.Cu" "F.Mask" "F.Paste")
			(net "P1V8_STBY")
		)
		(pad "2" smd rect
			(at 0.0635 0 270)
			(size 0.1778 0.254)
			(layers "F.Cu" "F.Mask" "F.Paste")
			(net "P1V8_STBY_CC")
		)
	)
)
